5
5
4
4
3
3
2
2
1
1
D D
C C
B B
A A
PROJECT NAME: GRAND TETONPCB SIZE: 39.3*86.15PCB REV: DPCB LAYER: 4LAST UPDATE: 2022/12/01
PVT CHANGE
SizeDoc NumberRevDate: SheetofReviewerDesignerDepartmentProject
Page TitleCCBU
<Doc>DA Tuesday, August 29, 2023<Designer>1 18<Title>COVER PAGE<Reviewer> SizeDoc NumberRevDate: SheetofReviewerDesignerDepartmentProject
Page TitleCCBU
<Doc>DA Tuesday, August 29, 2023<Designer>1 18<Title>COVER PAGE<Reviewer> SizeDoc NumberRevDate: SheetofReviewerDesignerDepartmentProject
Page TitleCCBU
<Doc>DA Tuesday, August 29, 2023<Designer>1 18<Title>COVER PAGE<Reviewer>



5
5
4
4
3
3
2
2
1
1
D D
C C
B B
A A
INDEX
 001  COVER PAGE 002  PAGE INDEX 003  BLOCK DIAGRAM 004  BLANK 005  SLIMSAS CONN 006  PFR_LED 007  SYSTEM STATUS LED 008  I/O EXPENDER 009  THERMAL SENSOR 010  BLANK 011  EFUSE 012  USB DEBUG 013  FRU 014  ESD 015  BLANK 016  SCREW HOLE 017  LOSS COUPON 018  DUMMY SYMBOL
SizeDoc NumberRevDate: SheetofReviewerDesignerDepartmentProject
Page TitleCCBU
<Doc>DA Tuesday, August 29, 2023<Designer>2 18<Title>PAGE INDEX<Reviewer> SizeDoc NumberRevDate: SheetofReviewerDesignerDepartmentProject
Page TitleCCBU
<Doc>DA Tuesday, August 29, 2023<Designer>2 18<Title>PAGE INDEX<Reviewer> SizeDoc NumberRevDate: SheetofReviewerDesignerDepartmentProject
Page TitleCCBU
<Doc>DA Tuesday, August 29, 2023<Designer>2 18<Title>PAGE INDEX<Reviewer>



5
5
4
4
3
3
2
2
1
1
D D
C C
B B
A A
BLOCKDIAGRAM SizeDoc NumberRevDate: SheetofReviewerDesignerDepartmentProject
Page TitleCCBU
<Doc>DA Tuesday, August 29, 2023<Designer>3 18<Title>BLOCK DIGRAM<Reviewer> SizeDoc NumberRevDate: SheetofReviewerDesignerDepartmentProject
Page TitleCCBU
<Doc>DA Tuesday, August 29, 2023<Designer>3 18<Title>BLOCK DIGRAM<Reviewer> SizeDoc NumberRevDate: SheetofReviewerDesignerDepartmentProject
Page TitleCCBU
<Doc>DA Tuesday, August 29, 2023<Designer>3 18<Title>BLOCK DIGRAM<Reviewer>



5
5
4
4
3
3
2
2
1
1
D D
C C
B B
A A
SizeDoc NumberRevDate: SheetofReviewerDesignerDepartmentProject
Page TitleCCBU
<Doc>DA Tuesday, August 29, 2023<Designer>4 18<Title>BLANK<Reviewer> SizeDoc NumberRevDate: SheetofReviewerDesignerDepartmentProject
Page TitleCCBU
<Doc>DA Tuesday, August 29, 2023<Designer>4 18<Title>BLANK<Reviewer> SizeDoc NumberRevDate: SheetofReviewerDesignerDepartmentProject
Page TitleCCBU
<Doc>DA Tuesday, August 29, 2023<Designer>4 18<Title>BLANK<Reviewer>



5
5
4
4
3
3
2
2
1
1
D D
C C
B B
A A
Place CAP near J1 pin B17 Place CAP near J1 pin B18
SLIMSAS CONN
PVT BOM CHANGE
USB2_DP [14]USB2_DN [14]PRSNT_DBV2_SLIMSAS [12]SMB_SCL [8,9,12,13]FM_PFR_LED_AMBER_N [6]RST_SMB_N [8]FM_PFR_LED_BLUE_N [6]SMB_SDA [8,9,12,13]UART_DEBUG_TX [12]UART_DEBUG_RX [12]P5V_STBYP3V3_STBYP5V_STBYP3V3_STBYP5V_STBYP5V_STBYP3V3_STBYSizeDoc NumberRevDate: SheetofReviewerDesignerDepartmentProject
Page TitleCCBU
<Doc>DA Tuesday, August 29, 2023<Designer>5 18<Title>SLIMSAS CONN<Reviewer> SizeDoc NumberRevDate: SheetofReviewerDesignerDepartmentProject
Page TitleCCBU
<Doc>DA Tuesday, August 29, 2023<Designer>5 18<Title>SLIMSAS CONN<Reviewer> SizeDoc NumberRevDate: SheetofReviewerDesignerDepartmentProject
Page TitleCCBU
<Doc>DA Tuesday, August 29, 2023<Designer>5 18<Title>SLIMSAS CONN<Reviewer>C3C0603_H4020%10UF16VC1C0603_H4020%10UF16V
J1SCONN38_PSL060-3847-T11-1HGND_A1A1HS_A2A2HS_A3A3GND_A4A4HS_A5A5HS_A6A6GND_A7A7SB_A8A8SB_A9A9SB_A10A10SB_A11A11SB_A12A12GND_A13A13HS_A14A14HS_A15A15GND_A16A16HS_A17A17HS_A18A18GND_A19A19GND_B1B1HS_B2B2HS_B3B3GND_B4B4HS_B5B5HS_B6B6GND_B7B7SB_B8B8SB_B9B9SB_B10B10SB_B11B11SB_B12B12GND_B13B13HS_B14B14HS_B15B15GND_B16B16HS_B17B17HS_B18B18GND_B19B19G1G1G2G2G3G3G4G4C4 2.2UF10%C0402-0201C2C0402-020110%0.1UF25V
0 5% R0402-0201R680 5% R0402-0201R67USB2_DPUSB2_DNFM_PFR_LED_AMBER_NFM_PFR_LED_BLUE_NRST_SMB_NPRSNT_DBV2_SLIMSASSMB_SWB_SCLSMB_SWB_SDAUART_DEBUG_TXUART_DEBUG_RX



5
5
4
4
3
3
2
2
1
1
D D
C C
B B
A A
The specification of D1
PFR LED
FM_PFR_LED_AMBER_N[5]FM_PFR_LED_BLUE_N[5] P5V_STBYP5V_STBY
SizeDoc NumberRevDate: SheetofReviewerDesignerDepartmentProject
Page TitleCCBU
<Doc>DA Tuesday, August 29, 2023<Designer>6 18<Title>PFR_LED<Reviewer> SizeDoc NumberRevDate: SheetofReviewerDesignerDepartmentProject
Page TitleCCBU
<Doc>DA Tuesday, August 29, 2023<Designer>6 18<Title>PFR_LED<Reviewer> SizeDoc NumberRevDate: SheetofReviewerDesignerDepartmentProject
Page TitleCCBU
<Doc>DA Tuesday, August 29, 2023<Designer>6 18<Title>PFR_LED<Reviewer>
U1<Part Number>BSS138KNIGDSU2<Part Number>BSS138KNIGDSR2 R0402-02015%0NIYellowBlueD1LED_BLUE/YELLOW<Part Number>NI123R4 R0402-02015%0NIR34705%R0805NIR17501%R0603NIFM_PFR_LED_AMBER_RFM_PFR_LED_AMBER_NFM_PFR_LED_AMBER_R_NFM_PFR_LED_BLUE_RFM_PFR_LED_BLUE_NFM_PFR_LED_BLUE_R_N



5
5
4
4
3
3
2
2
1
1
D D
C C
B B
A A
The specification of D2
The specification of D3
STATUS LED
DVT CHANGE
CHANGE LED SYMBOL FORSOLVE LED SHIFT DFM.
WILL NOT CHANGEMATIRIAL IN THIS STAGE.
SYSTEM_FAULT_ID_LED_R1[8]PWR_LED_R1[8]
P5V_STBYP5V_STBYP3V3_STBY
P5V_STBYP5V_STBYP3V3_STBY
SizeDoc NumberRevDate: SheetofReviewerDesignerDepartmentProject
Page TitleCCBU
<Doc>DA Tuesday, August 29, 2023<Designer>7 18<Title>SYSTEM STATUS LED<Reviewer> SizeDoc NumberRevDate: SheetofReviewerDesignerDepartmentProject
Page TitleCCBU
<Doc>DA Tuesday, August 29, 2023<Designer>7 18<Title>SYSTEM STATUS LED<Reviewer> SizeDoc NumberRevDate: SheetofReviewerDesignerDepartmentProject
Page TitleCCBU
<Doc>DA Tuesday, August 29, 2023<Designer>7 18<Title>SYSTEM STATUS LED<Reviewer>
D
G
S
U32N7002KW<Part Number>DGS
D
G
S
U42N7002KW<Part Number>DGS D3LED_BLUE<Part Number>ACR11 360 R06031%R9R0402-02015%10KNIR8100K1%R0402-0201R12100KR0402-02011%
R7 360 R06031%D2LED_YELLOW<Part Number>ACR6100K1%R0402-0201R104.75KR0402-02011%
R5R0402-02015%10KNISYSTEM_FAULT_ID_LED_R1_NSYSTEM_FAULT_ID_LED_R2_NSYSTEM_FAULT_ID_LED_R1PWR_LED_R1_NPWR_LED_R2_NPWR_LED_R1



5
5
4
4
3
3
2
2
1
1
D D
C C
B B
A A
I/O EXPENDER
SLAVE ADDRESS
1 A0 A11 01 1 R/W#
I2C MASTER：
I2C SLAVE  ADDRESS:
SLIMSAS(J1)
0XEE
PVT CHANGE
SMB_SCL [5,9,12,13]SMB_SDA [5,9,12,13]RST_SMB_N[5] SYSTEM_FAULT_ID_LED_R1 [7]PWR_LED_R1 [7]PCA9539_A1[8] PCA9539_A0 [8]REV_ID<0>[8]REV_ID<1>[8]REV_ID<2>[8]RST_SMB_R_N [8]PCA9539_A1 [8]PCA9539_A0 [8]REV_ID<0> [8]REV_ID<1> [8]REV_ID<2> [8]
RST_SMB_R_N[8] P3V3_STBYP3V3_STBYSizeDoc NumberRevDate: SheetofReviewerDesignerDepartmentProject
Page TitleCCBU
<Doc>DA Tuesday, August 29, 2023<Designer>8 18<Title>I/O EXPENDER<Reviewer> SizeDoc NumberRevDate: SheetofReviewerDesignerDepartmentProject
Page TitleCCBU
<Doc>DA Tuesday, August 29, 2023<Designer>8 18<Title>I/O EXPENDER<Reviewer> SizeDoc NumberRevDate: SheetofReviewerDesignerDepartmentProject
Page TitleCCBU
<Doc>DA Tuesday, August 29, 2023<Designer>8 18<Title>I/O EXPENDER<Reviewer>R21R0402-02015%10KR14 R0402-02010 5%R16 33.2 R0402-02011%R15 R0402-02010 5%R1910K1%R0402-0201R22R0402-02015%10KC50.1UFC0402-020110%16VR2010K1%R0402-0201R17 33.2 R0402-02011%
R26R0402-02015%100KNIR23R0402-02015%10KNIR24R0402-02011%10KNI
R13 R0402-02015%0
R27R0402-02015%100KNIC6100PFC0402-02015%50V
U5PCA9539RPW<Part Number>INT1A12RESET3IO0_04IO0_15IO0_26IO0_37IO0_48IO0_59IO0_610IO0_711VSS12IO1_013IO1_114IO1_215IO1_316IO1_417IO1_518IO1_619IO1_720A021SCL22SDA23VDD24
R28R0402-02015%100KR25R0402-02011%10KNIR1810K1%R0402-0201NISMB_EXP_SDASMB_EXP_SCLRST_SMB_NPCA9539_A0PCA9539_A1REV_ID<2>REV_ID<1>REV_ID<0>SYSTEM_FAULT_ID_LED_R1PWR_LED_R1RST_SMB_R_NPCA9539_A1PCA9539_A0REV_ID<0>REV_ID<1>REV_ID<2>
SYSTEM_FAULT_ID_LEDPWR_LEDRST_SMB_R_N



5
5
4
4
3
3
2
2
1
1
D D
C C
B B
A A
THERMAL SENSOR
SLAVE ADDRESS
R/W#A00
SLIMSAS(J1)
0 A11
I2C SLAVE  ADDRESS:
1
0X90
I2C MASTER：
A2
PVT BOM CHANGE
SMB_SDA[5,8,12,13]SMB_SCL[5,8,12,13]P3V3_STBYP3V3_STBYP3V3_STBYP3V3_STBY
SizeDoc NumberRevDate: SheetofReviewerDesignerDepartmentProject
Page TitleCCBU
<Doc>DA Tuesday, August 29, 2023<Designer>9 18<Title>THERMAL SENSOR<Reviewer> SizeDoc NumberRevDate: SheetofReviewerDesignerDepartmentProject
Page TitleCCBU
<Doc>DA Tuesday, August 29, 2023<Designer>9 18<Title>THERMAL SENSOR<Reviewer> SizeDoc NumberRevDate: SheetofReviewerDesignerDepartmentProject
Page TitleCCBU
<Doc>DA Tuesday, August 29, 2023<Designer>9 18<Title>THERMAL SENSOR<Reviewer>
R29 R0402-02015%10KC70.1UFC0402-020110%16VR38R0402-02015%100KR35 R0402-02015%33R314.7K1%R0402-0201R32R0402-02015%10KNIR304.7K1%R0402-0201R34R0402-02015%10KNIR36 R0402-02015%33U6LM75BD<Part Number>SDA1SCL2OS3GND4A25A16A07VCC8R37R0402-02015%100KR39R0402-02015%100KR33R0402-02015%10KNISMB_SDASMB_SCLTHERMAL_ADDR_A0THERMAL_ADDR_A1THERMAL_ADDR_A2SMB_TMP75_SCLSMB_TMP75_SDATHERMAL_OS



5
5
4
4
3
3
2
2
1
1
D D
C C
B B
A A
SizeDoc NumberRevDate: SheetofReviewerDesignerDepartmentProject
Page TitleCCBU
<Doc>DA Tuesday, August 29, 2023<Designer>10 18<Title>BLANK<Reviewer> SizeDoc NumberRevDate: SheetofReviewerDesignerDepartmentProject
Page TitleCCBU
<Doc>DA Tuesday, August 29, 2023<Designer>10 18<Title>BLANK<Reviewer> SizeDoc NumberRevDate: SheetofReviewerDesignerDepartmentProject
Page TitleCCBU
<Doc>DA Tuesday, August 29, 2023<Designer>10 18<Title>BLANK<Reviewer>



5
5
4
4
3
3
2
2
1
1
D D
C C
B B
A A
Set the limite current at 1100 mA
EFUSE
Place CAP near U7.6
PVT BOM CHANGE
P3V3_STBYP3V3_STBYP5V_STBY_DEBUGP5V_STBYP5V_STBYP5V_STBY_DEBUG
SizeDoc NumberRevDate: SheetofReviewerDesignerDepartmentProject
Page TitleCCBU
<Doc>DA Tuesday, August 29, 2023<Designer>11 18<Title>EFUSE<Reviewer> SizeDoc NumberRevDate: SheetofReviewerDesignerDepartmentProject
Page TitleCCBU
<Doc>DA Tuesday, August 29, 2023<Designer>11 18<Title>EFUSE<Reviewer> SizeDoc NumberRevDate: SheetofReviewerDesignerDepartmentProject
Page TitleCCBU
<Doc>DA Tuesday, August 29, 2023<Designer>11 18<Title>EFUSE<Reviewer>
R42R0402-02010.1%18.2KR40R0402-020110K5% C1622UF20%16VC0805_H57C922UF20%16VC0805_H57C1022UF20%16VC0805_H57C1422UF20%16VC0805_H57C1222UF20%16VC0805_H57R41R0402-020110K5%C8 2.2UF10%C0402-0201C1522UF20%16VC0805_H57C13 2.2UF10%C0402-0201NCP380HSNAJAAT1GU7<Part Number>FLAG_N4IN1ILIM5OUT6EN3GND2NCO380_ENNCP380_FLT_NNCP380_ILIM



5
5
4
4
3
3
2
2
1
1
D D
C C
B B
A A
USB DEBUG
PVT BOM CHANGE
USB2_DEBUG_DN[14]USB2_DEBUG_DP[14] SMB_SDA [5,8,9,13]SMB_SCL [5,8,9,13]UART_DEBUG_TX [5]UART_DEBUG_RX [5]PRSNT_DBV2_SLIMSAS [5]SMB_IO_DEBUG_CARD_SCL [14]SMB_IO_DEBUG_CARD_SDA [14]UART_DEBUG_R_TX [14]UART_DEBUG_R_RX [14]P5V_STBY_DEBUGP3V3_STBYP5V_STBYP3V3_STBY
SizeDoc NumberRevDate: SheetofReviewerDesignerDepartmentProject
Page TitleCCBU
<Doc>DA Tuesday, August 29, 2023<Designer>12 18<Title>USB DEBUG<Reviewer> SizeDoc NumberRevDate: SheetofReviewerDesignerDepartmentProject
Page TitleCCBU
<Doc>DA Tuesday, August 29, 2023<Designer>12 18<Title>USB DEBUG<Reviewer> SizeDoc NumberRevDate: SheetofReviewerDesignerDepartmentProject
Page TitleCCBU
<Doc>DA Tuesday, August 29, 2023<Designer>12 18<Title>USB DEBUG<Reviewer>R45R0402-02015%4.7KQ1ADMN53D0LDW-7<Part Number>S11G12D16R65 R0402-02010 5%R46R0402-020110K5%NIR48 33.2 R0402-02011%Q1BDMN53D0LDW-7<Part Number>D23G25S24
J2CONN9_AUSB0043-P033AAUSB0043-P033AVBUS1D-2D+3GND_DRAIN7SSRX-5SSRX+6GND4SSTX-8SSTX+9G1G1G2G2G3G3G4G4R66 22 1% R0402-0201R47R0402-020110K5%NIR49 33.2 R0402-02011%R43R0402-02015%10KNIR50R0402-02015%100KR44R0402-02015%4.7KUSB2_DEBUG_DNUSB2_DEBUG_DPSMB_IO_DEBUG_CARD_SCLSMB_IO_DEBUG_CARD_SDAUART_DEBUG_R_TXUART_DEBUG_R_RXPRSNT_DBV2_USB_NPRSNT_DBV2_USB



5
5
4
4
3
3
2
2
1
1
D D
C C
B B
A A
FRU
0XA2
1
SLIMSAS(J1)
A200
I2C MASTER：
I2C SLAVE  ADDRESS:
1 R/W# A1
SLAVE ADDRESS
A0
SMB_SCL[5,8,9,12]SMB_SDA[5,8,9,12]P3V3_STBYP3V3_STBY
SizeDoc NumberRevDate: SheetofReviewerDesignerDepartmentProject
Page TitleCCBU
<Doc>DA Tuesday, August 29, 2023<Designer>13 18<Title>FRU<Reviewer> SizeDoc NumberRevDate: SheetofReviewerDesignerDepartmentProject
Page TitleCCBU
<Doc>DA Tuesday, August 29, 2023<Designer>13 18<Title>FRU<Reviewer> SizeDoc NumberRevDate: SheetofReviewerDesignerDepartmentProject
Page TitleCCBU
<Doc>DA Tuesday, August 29, 2023<Designer>13 18<Title>FRU<Reviewer>
R584.7KR0402-02015%R6110K5%R0402-0201R534.7KR0402-02015%NI R6210K5%R0402-0201R544.7KR0402-02015%NIR60 33 R0402-02011%R6310K5%R0402-0201NIU9M24C64-WMN6TP<Part Number>VCC8WC#7SCL6SDA5VSS4E23E12E01R564.7KR0402-02015%NIR554.7KR0402-02015%NIR6410K5%R0402-0201R574.7KR0402-02015%NIC110.1UF16V10%C0402-0201R59 33 R0402-02011%PD_FRU_A0PD_FRU_A1SMB_SCLSMB_FRU_SCLPD_FRU_A2SMB_SDASMB_FRU_SDAPD_FRU_WP



5
5
4
4
3
3
2
2
1
1
D D
C C
B B
A A
ESD
SMB_IO_DEBUG_CARD_SCL[12]SMB_IO_DEBUG_CARD_SDA [12]UART_DEBUG_R_TX[12]UART_DEBUG_R_RX [12]USB2_DEBUG_DP[12,14]USB2_DEBUG_DN [12,14]
USB2_DN[5] USB2_DEBUG_DN [12,14]USB2_DP[5] USB2_DEBUG_DP [12,14]
P5V_STBY_DEBUGP5V_STBY_DEBUGP5V_STBY_DEBUG
SizeDoc NumberRevDate: SheetofReviewerDesignerDepartmentProject
Page TitleCCBU
<Doc>DA Tuesday, August 29, 2023<Designer>14 18<Title>BLANK<Reviewer> SizeDoc NumberRevDate: SheetofReviewerDesignerDepartmentProject
Page TitleCCBU
<Doc>DA Tuesday, August 29, 2023<Designer>14 18<Title>BLANK<Reviewer> SizeDoc NumberRevDate: SheetofReviewerDesignerDepartmentProject
Page TitleCCBU
<Doc>DA Tuesday, August 29, 2023<Designer>14 18<Title>BLANK<Reviewer>
U11PRTR5V0U2X<Part Number>IO12GND1VCC4IO23
R52 0 R04025%L1DLW21SN670HQ2NI320MA<Part Number>4321
U8PRTR5V0U2X<Part Number>IO12GND1VCC4IO23
R51 0 R04025%
U10PRTR5V0U2X<Part Number>IO12GND1VCC4IO23



5
5
4
4
3
3
2
2
1
1
D D
C C
B B
A A
SizeDoc NumberRevDate: SheetofReviewerDesignerDepartmentProject
Page TitleCCBU
<Doc>DA Tuesday, August 29, 2023<Designer>15 18<Title>BLANK<Reviewer> SizeDoc NumberRevDate: SheetofReviewerDesignerDepartmentProject
Page TitleCCBU
<Doc>DA Tuesday, August 29, 2023<Designer>15 18<Title>BLANK<Reviewer> SizeDoc NumberRevDate: SheetofReviewerDesignerDepartmentProject
Page TitleCCBU
<Doc>DA Tuesday, August 29, 2023<Designer>15 18<Title>BLANK<Reviewer>



5
5
4
4
3
3
2
2
1
1
D D
C C
B B
A A
Tooling HolesTHUMB SCREW HOLE
SCREW HOLE SizeDoc NumberRevDate: SheetofReviewerDesignerDepartmentProject
Page TitleCCBU
<Doc>DA Tuesday, August 29, 2023<Designer>16 18<Title>SCREW HOLE<Reviewer> SizeDoc NumberRevDate: SheetofReviewerDesignerDepartmentProject
Page TitleCCBU
<Doc>DA Tuesday, August 29, 2023<Designer>16 18<Title>SCREW HOLE<Reviewer> SizeDoc NumberRevDate: SheetofReviewerDesignerDepartmentProject
Page TitleCCBU
<Doc>DA Tuesday, August 29, 2023<Designer>16 18<Title>SCREW HOLE<Reviewer>
H2HOLE_TOOLINGD125N_T2-0NIH11HOLE_C8D3_5B8_OB3-5XC4N_NPMNIH3HOLE_TOOLINGD125N_T2-0NIH12HOLE_C8D3_5B8_OB3-5XC4N_NPMNIH9GND_C10D4B10_OB3-5XC5BNI H4HOLE_TOOLINGD125N_T2-0NIH10GND_C10D4B10_OB3-5XC5BNI



5
5
4
4
3
3
2
2
1
1
D D
C C
B B
A A
TDR
LOSS COUPON
Delta-L
PVT CHANGE
GND_TDRGND_TDRGND_TDRGND_TDRGND1GND1GND1GND1
SizeDoc NumberRevDate: SheetofReviewerDesignerDepartmentProject
Page TitleCCBU
<Doc>DA Tuesday, August 29, 2023<Designer>17 18<Title>LOSS COUPON<Reviewer> SizeDoc NumberRevDate: SheetofReviewerDesignerDepartmentProject
Page TitleCCBU
<Doc>DA Tuesday, August 29, 2023<Designer>17 18<Title>LOSS COUPON<Reviewer> SizeDoc NumberRevDate: SheetofReviewerDesignerDepartmentProject
Page TitleCCBU
<Doc>DA Tuesday, August 29, 2023<Designer>17 18<Title>LOSS COUPON<Reviewer>
X2TP_TDR_4P_DIPP12P23S11S24 J6DELTA-L 4.02_N23_G31_P1J7DELTA-L 4.02_N23_G31_P1J3TDR_3P_C85P67_141_100M_QGND1IO12IO23J4TDR_3P_C85P67_141_100M_QGND1IO12IO23 J5DELTA-L 4.02_N23_G31_P1X1TP_TDR_4P_DIPP12P23S11S24 J8DELTA-L 4.02_N23_G31_P1TDR_DIFF_85_TOP_DPTDR_SE_50_OHM_TOPTDR_DIFF_85_TOP_DNTDR_SE_50_OHM_BOTDelta_L_85_5inch_TOP_DPDelta_L_85_5inch_TOP_DNDelta_L_85_10inch_TOP_DPDelta_L_85_10inch_TOP_DN



5
5
4
4
3
3
2
2
1
1
D D
C C
B B
A A
PB-E1WEEE
REWORK LABELPCBA_LABEL
Quanta LOGO(TOP) PCB_VENDER_LOGO
DUMMY SYMBOL SizeDoc NumberRevDate: SheetofReviewerDesignerDepartmentProject
Page TitleCCBU
<Doc>DA Tuesday, August 29, 2023<Designer>18 18<Title>DUMMY SYMBOL<Reviewer> SizeDoc NumberRevDate: SheetofReviewerDesignerDepartmentProject
Page TitleCCBU
<Doc>DA Tuesday, August 29, 2023<Designer>18 18<Title>DUMMY SYMBOL<Reviewer> SizeDoc NumberRevDate: SheetofReviewerDesignerDepartmentProject
Page TitleCCBU
<Doc>DA Tuesday, August 29, 2023<Designer>18 18<Title>DUMMY SYMBOL<Reviewer>
ME_PART SymbolME2WEEEME_PART SymbolME7MACLABEL_17X12ME_PART SymbolME3PB-E1_SMALLME_PART SymbolME8REWORKLABEL_39-5X6-5ME_PART SymbolME4PCB_VENDOR_LOGO_15X8ME_PART SymbolME1QUANTA_LOGO_2X7-6ME_PART SymbolME5SNLABEL_7X7ME_PART SymbolME6PNLABEL_23-5X5